M48
;Layer_Color=9474304
;FILE_FORMAT=2:5
INCH,LZ
;TYPE=PLATED
T01F00S00C0.00800
T02F00S00C0.01000
T03F00S00C0.02166
T06F00S00C0.02992
T07F00S00C0.03543
T08F00S00C0.04016
T09F00S00C0.04331
T10F00S00C0.05906
T11F00S00C0.06693
T12F00S00C0.07087
T13F00S00C0.07900
T14F00S00C0.11811
T15F00S00C0.12200
T16F00S00C0.16535
;TYPE=NON_PLATED
T17F00S00C0.04331
T18F00S00C0.06299
T19F00S00C0.10000
T20F00S00C0.11800
T21F00S00C0.12520
%
T01
X0622753Y-0353307
X0623228Y-0343307
X0622677Y-0333307
X0622221Y-0313481
X0619148Y-0302756
X0610236Y-03
X0598898Y-0313307
X0598959Y-0333307
X0598819Y-0343307
X0598583Y-0353307
X0579072Y-035669
X056133Y-0356099
X0561024Y-0340158
X0555512
X0552756Y-0335827
X0544882Y-0336221
X0540551Y-0340945
X0535827Y-0345276
X0530315Y-0338976
X0521654Y-0336221
X0513386
X050541Y-0336036
X0499302Y-0353737
X0499525Y-0358855
X0493234Y-035662
X0533931Y-0356296
X0543698Y-0358659
X0543718Y-035354
X0544882Y-0305118
X0552756
X0551968Y-0297638
X0546457Y-0297342
X0540945
X0534814Y-029719
X0536221Y-0300787
X0530709
X052896Y-0296841
X0522835Y-0297736
X0516929Y-029813
X0513406Y-0302902
X0505512Y-030315
X050748Y-029813
X0503346Y-0297967
X0501181Y-029813
X0495276
X0495866Y-0303543
X0492323
X049311Y-0310236
X0489567
X049662Y-0310492
X0498425Y-0307087
X0484842Y-0317717
X0477362Y-0313767
X0473819Y-0315354
X0479331Y-0294626
X0476772Y-0291929
X0483465Y-0291535
X0548819Y-0300787
X0562205Y-0297736
X056811
X0570472
X0576378
X0569685Y-030315
X0570079Y-0309921
X0568898Y-0319009
X0593307Y-0292126
X0466142Y-0294685
Y-0298228
X0461024Y-0302756
X0461417Y-0305118
Y-0312099
X0454775Y-0308565
X0432835Y-0291755
X0381595Y-0315042
X0376477
X0370178
X0364272
X0357973Y-0315042
X0352461Y-0315042
X0342618Y-0315081
X0332382Y-0315042
X032254Y-0315042
X0324184Y-0302194
X0320472Y-0299569
X0315333Y-029943
X0314961Y-0293701
X0325776
X0333465Y-0292913
X0336811Y-0299399
X033937Y-0298819
X0345161Y-0292913
X0355741Y-0296063
X0359652Y-0326841
X0362408
X0365354Y-0330315
X036811
X0370079Y-0332283
X0371359Y-0328034
X0374114
X0377658Y-0327985
X0381989Y-0331971
X0380807Y-0346144
X0377658
X037687Y-0348458
X0374902
X0374114Y-0346144
X0371359
X0370472Y-0348425
X0368294Y-0348913
X0367422Y-0346144
X0364666
X0363878Y-0348458
X036191
X0360729Y-0346144
X0357973
X0356792Y-0348458
X0354823Y-0348851
X0354036Y-0346144
X035128
X0349705Y-0348064
X0352106Y-0332482
X0353543Y-0330315
X0356299
X0348425Y-032874
X0344882Y-0328346
X0343012Y-0332365
X0332776
X0322933
X0364173Y-0332283
X0369703Y-0326432
X0381989Y-0348458
X0414772Y-0353273
X0415623Y-0358391
X044915Y-0355832
X04609Y-0354061
X0460678Y-0359179
X0273425Y-0374655
X0269502Y-0374291
X025689Y-0374655
X0253655Y-0374421
X0241929Y-0374655
X0237992
X0222638
X0218445Y-0374108
X0210433Y-0374655
X0206496
X0196701Y-0370523
X0198392Y-0366842
X0190354Y-0377411
X0178543
X0181534Y-0387757
X0174941Y-03906
X0163071Y-039073
X0158661Y-0389616
X0156693
X0154724
Y-0386466
X0156693
X0158661
X015748Y-0361811
X0155512
Y-0358661
X015748
X0202441Y-03906
X0212795Y-0387253
X0215945
X0216162Y-0390947
X0226063Y-0390722
X0229331Y-0387253
X023248
X0235144Y-0390416
X0246339Y-0386975
X024941Y-0387253
X0251456Y-0390009
X0259285Y-0390247
X0262006Y-0387255
X0265158Y-0387253
X0267204Y-0390009
X0281201
X0280414Y-0293782
X0284646Y-0291732
X0308268Y-03
X0246162Y-0293733
X0153543Y-0358661
Y-0361811
X0141587Y-0352161
X0142126Y-0348031
X0029543Y-0345214
X0026772Y-0348819
X0027559Y-0337402
X0022047Y-0335433
X0019976Y-0326772
Y-0307087
X0027067Y-0298727
X0014173Y-029432
X001063Y-0292126
X0004331Y-0344488
X0002097Y-0349213
X-0001181Y-0352831
X0012598Y-0349213
X-0018601Y-0349409
X-0023622Y-034252
Y-0339567
Y-033563
Y-0294291
Y-0290354
Y-0286417
Y-028248
X-0004724Y-0283071
X-0023622Y-0241142
Y-0237205
Y-0233268
Y-0229331
Y-0187992
Y-0184055
Y-0181102
Y-0177165
X-001063Y-0178347
X-0007874Y-0188976
X0009843Y-0185755
X001378Y-0190551
X0019682Y-019252
X0019976Y-0200787
X001063Y-0197638
X0030709Y-0190411
X0033071Y-0185755
X0035827
X0027165Y-0179134
X0019976Y-0220472
X0019685Y-023937
X0014665Y-0237402
X0010007Y-0234968
X0005584Y-0238905
X0000288Y-0234968
X003622Y-0235039
X0036614Y-0232677
X003512Y-0228937
X0035039Y-0237402
X0019976Y-0252953
Y-0272638
X0027067Y-0282677
X0035039Y-0285827
Y-0289961
X0044001Y-0137747
X0058407Y-0137589
X0068889Y-0137453
X0071202Y-0138095
X0079044Y-0137936
X0081044Y-0139557
X0083044Y-0137936
X0085044Y-0139557
X0087044Y-0137936
X0089044Y-0139557
X0091044Y-0137936
X0126307Y-0136224
X0129063Y-0136618
X0133099Y-0136519
X0151808Y-0137205
X0150394Y-0140157
X0162241Y-0140004
X0165587Y-0139961
X0170311
X0172674Y-0138386
X0178185Y-0136811
X0186847Y-0135236
X0199193Y-013868
X0204193Y-0138257
X0217405Y-0138189
X0223209Y-0137815
X0228209Y-0138721
X0233209Y-0139232
X0238189Y-0138976
X027559Y-0184252
X0274803Y-0188583
X028189
Y-0200771
X027559Y-0199606
X0275503Y-0195276
X0288583
X0291831Y-0197012
X028937Y-0200394
Y-0205906
X0295669Y-0191339
X0292815Y-0187106
X0299606Y-0185433
X0309055Y-0195669
X0307087Y-0198819
X0309449Y-0211811
X0309782Y-0243307
X0293307Y-0237008
X0288583Y-0237402
X0281496
X0277165Y-0236221
X0279134Y-0230315
X0280315Y-0226378
X026358Y-0226943
X0258922Y-0226766
X0259022Y-0236566
X0263622Y-0236666
X0263322Y-0246466
X0258622
X025876Y-0256529
X0263681
X0262922Y-026504
X0258702Y-0264859
X0258622Y-0276066
X0263322
X0263122Y-0285766
X0258622
X0280414Y-0287478
Y-0283478
X0280382Y-0274277
X0298819Y-0269685
X0276755Y-0246539
X0274719Y-0244928
X0243996Y-0248655
Y-0252592
X0245965Y-0250655
Y-0254655
X0244028Y-0258497
X0245965Y-0260497
X0244028Y-0262466
X0245965Y-0264497
X0240158Y-027874
X0230406Y-0251861
X0230709Y-0242913
X0231102Y-0239764
X0230165Y-0235119
X0230251Y-0232266
X0204331Y-0232677
X0203937Y-0235827
Y-0238189
X0203805Y-0240564
X0203937Y-0242913
X0203689Y-0248906
X0203805Y-0252182
X0203937Y-0254724
X0261024Y-0200394
X0314675Y-0198819
X0319291Y-019685
X0322835Y-0196063
X033122Y-0196266
X0337774Y-0196489
X0341774Y-0196326
X0343701Y-0200394
X0347638Y-0202756
X0343701Y-0209449
X035748Y-0214567
X0368232Y-0217717
X0375197Y-022126
X0382776Y-0221555
X0390158Y-0217717
X04Y-0219291
X0407874Y-0216535
X040876Y-0238189
X0398472Y-0235531
X0389764Y-0234252
X0383465
X0386614Y-0237402
Y-0231102
X0373093Y-0232972
X0367654Y-0236614
X0378937Y-0249803
X038189Y-0254331
X0386615Y-0249113
X0390896Y-0249065
X039685Y-0249016
X0401575Y-0249213
X0418898Y-0245276
X0429134Y-024685
X0432283Y-0254724
X0445768Y-0254381
X0451674
Y-024457
X0445768
Y-0234727
X0451674
Y-0224885
X0445768
X043002Y-0222916
Y-0220948
Y-0218979
Y-021701
X0427953Y-0206299
X0424409Y-0205512
X0428346Y-0187795
X0426772Y-0179528
X0419798Y-0176745
X0421313Y-0174784
X0422835Y-0166284
X0427843Y-0166966
X0393701Y-0168898
X0383071Y-016811
X0378594Y-0166966
X0378346Y-0161811
X0383083Y-0161839
X0388189Y-0162205
X0373228Y-0162598
X0366043Y-0153937
X0369981Y-0179215
X0369685Y-0183841
X0359874
X0360138Y-0179215
X0350327
Y-0183546
X0340256Y-0183841
X0337795Y-0181102
X0334252Y-0180315
X0330705Y-0179215
X0329528Y-018189
X0331091Y-018405
X0327658Y-0184678
X0324705
X0320761Y-0183851
X0320473Y-0179117
X0326705Y-0179059
X0340847Y-0179215
X0342808Y-0166966
X0348031Y-0165748
X0323622Y-0166535
X032126Y-0166142
X0317828Y-016126
X0313878Y-0161597
X0310236Y-0165748
X0313386Y-0212598
X0312322Y-0236221
X0317009Y-0239764
X0319685Y-0245276
X032559Y-0246324
X0334842Y-0247244
X0333714Y-0239764
X0341274Y-0242913
X0340786Y-0235827
X032559Y-0232344
X0321654Y-0232677
X0329134Y-022874
X0318989Y-0253024
X0337402Y-026063
X0341339Y-0277953
X033937Y-0286162
X0336614Y-0286221
X032185Y-0283465
X0320472Y-0287865
X0315945Y-0287795
X0313386Y-0283465
X0356693Y-0288583
X0364173Y-0280315
X0383071Y-0276772
X0391339Y-0277953
X0402756Y-0281102
X0432579Y-0283251
Y-02864
X043272Y-0289358
X0445768Y-028394
X0451674
Y-0275261
X0445768
Y-0264255
X0451674
X0462205Y-0255118
X0463453Y-0247883
X0464472Y-024554
X0462473Y-0277635
X0429528Y-0231496
X0399213Y-0193307
X0394193Y-019767
X0389567Y-019644
X0380363Y-019674
X0375698Y-01977
X037373Y-0202888
X0385541Y-020246
X0383572Y-0206205
X0384646Y-0184252
X038189Y-0183858
X0379496Y-0183803
Y-0179215
X0362598Y-0197244
X0481496
X0488189Y-0216535
X0500971Y-0219896
X0496063Y-0244094
X0495669Y-0255512
X0500049Y-0256633
X0502362Y-0257185
X0504331
X0507874Y-0255906
X0508268Y-0251673
X0513386Y-0254429
X051811Y-0255217
X0522047Y-0249705
X0524016Y-0243799
X0536614Y-0245374
X0538976Y-0250886
X0540945Y-0256004
X055Y-025561
X0550391Y-024331
X0564173Y-0255906
X0568898Y-0256791
X057126
X0578332Y-0261235
X0585039Y-0266142
Y-0272835
X0581496
X0583815Y-0275386
X0574406Y-0280807
X0567525Y-0286203
X055546Y-0284401
X0554724Y-0272441
X056063Y-0269291
X0548425Y-0269632
X0541411Y-0269932
X0536489Y-0269182
X0522047Y-0270866
X0541093Y-0284626
X058189Y-0290158
X0599044Y-0275032
X0604724Y-0274803
X0605512Y-0261024
Y-0256693
X0605317Y-0252756
X0604316Y-02466
X060315Y-0235946
X0596063Y-0239895
Y-0241995
X058189Y-0235925
X0584646Y-0225197
X0590188Y-0221161
X058937Y-0212992
X0588922Y-0206462
X058937Y-0201575
X0591339Y-0189764
X0583858Y-0192913
X0586221Y-017874
X058189Y-0174016
X0582165Y-0163898
X0586614Y-0158661
X0591339Y-0144488
X0611614Y-0186107
X0611811Y-022126
X0608661Y-0220472
X0616929Y-0225984
X0614822Y-0250158
X0618504Y-0252362
X0622101Y-025
X0596865Y-0266396
X0594765
X0579134Y-0214006
X0521654Y-0198819
X0513386Y-0199213
X0472047Y-0217323
Y-0219291
Y-022126
Y-0223228
X0470472Y-0246457
X0477165Y-0247244
X0476772Y-0254035
X0473622Y-0259055
X0480315Y-0259744
X0487402Y-0256988
X0486221Y-0265748
X0474409
X0476378Y-0273622
X0480315Y-0271752
X0473303Y-0276476
X0485827Y-0279429
X0494882Y-0262303
X0483831Y-0241339
X0622803Y-0241006
X0622835Y-0244094
Y-0235433
X0626987Y-0228346
X0624918Y-0211353
X0624938Y-0206373
X0624926Y-0201353
X0624938Y-0196373
X0625079Y-0173898
X0624685Y-0163898
X0594488Y-0132677
X0592913Y-0116535
X0597244Y-0108661
X0602105Y-0099109
X0603543Y-0087795
X0598397Y-0088288
X0595276Y-0079921
X0608268Y-0084252
X0613406Y-0089494
X0608405Y-0070079
X061811Y-0062205
X0476968Y-0076378
X0462992
X0464961Y-0125197
X0422835Y-0131791
X0418898Y-0129753
X0415748Y-0129609
X0400984Y-0127102
X0388713Y-0128731
X0383083Y-0128504
X0383465Y-0103543
X0390654Y-010451
X0418898Y-01
X0422047Y-0101969
X0355035Y-0105876
X0347244Y-0113189
X0347638Y-0119882
X032126Y-0114961
X0317323
X0262724Y-0107813
X0253082Y-0110236
X0245276Y-0115748
X0245325Y-0120837
X0238189Y-0107087
X0233071
X0228346Y-010748
X0223228
X0214173Y-0107087
X0211648Y-0103695
X0204331Y-0101575
X0197244Y-0102756
X0199193Y-0105925
X0197638Y-0097638
X019685Y-0094488
X0198524Y-0087795
X0189764Y-0088189
X018061Y-0087795
X0177559
X0182677Y-0094488
X0182283Y-0097244
X0181004Y-0101181
X0189764Y-0100787
X0192126Y-0111811
X0188028Y-0113583
X0173228Y-0117323
X0173461Y-0127362
X0178185Y-0133661
X0168343Y-0110827
X0164843Y-011404
X0160075Y-0112402
X0156926Y-0111614
X0158268Y-010748
X0161417
X016811Y-0103937
Y-0100132
X0161417Y-0095276
X0168504Y-0079528
Y-0073622
Y-007126
Y-0065354
X0168898Y-0049606
Y-0044094
X0168504Y-0037795
Y-003189
Y-0025984
X016811Y-0020079
Y-001063
X0168273Y-0006496
X016811Y-0004331
Y0001575
X0162598Y-0001575
Y-0009449
Y-0013189
X0156693Y-001811
X0155328Y-0026033
X0161417Y-0025984
X0155427Y-0033907
X0157087Y-0041732
X015748Y-0073228
X0209449Y-007441
Y-0072047
X0205118Y-007938
X0214173Y-0079134
X0209541Y-0058689
X021063Y-005315
X0210236Y-0044094
X0215354Y-0042126
X0220866Y-0039764
X0226378Y-0032677
X0216535Y-0025197
X0211024Y-002126
X0211811Y-0016535
X0214567Y-0011417
X0209055Y-000748
Y-0005512
X0209449Y-0003543
X0214173Y0001181
X0209449Y0007087
X0203937Y0001969
X0169291Y0009646
Y0013386
X0159843Y0009646
X0222351Y-0098694
X015315Y-0099691
Y-0103412
X0148425Y-0104336
X015315Y-0113386
X0152398Y-0117717
X0150233Y-0119882
X0149935Y-0124206
X0152904Y-0124213
X0153225Y-0121747
X0150233Y-0127362
X0150627Y-0130512
X014007Y-0132385
X0140116Y-0124048
X0133099Y-0119984
X0130245Y-012087
X0124016Y-0110236
X0098761Y-0117746
X0100729Y-0119871
X0098761Y-0121871
X0100729Y-0123872
X0098761Y-0125872
X0100729Y-0127872
X0098761Y-0129872
X0089312Y-012814
X0084981
X0080651
Y-0123809
X0084981
X0089312
Y-0119478
X0084981
X0080651
X0078918Y-0110029
X0082918
X0080981Y-0108061
X0084981
X0086981Y-0110029
X0088981Y-0108061
X0091044Y-0110061
X0087795Y-0099606
X005821Y-0108061
X0044621Y-0110628
X0044134Y-011508
X0052501Y-0119872
X0051287Y-0126878
X0057422Y-0128927
X0013386Y-0126878
X0038583Y-0058355
X0038613Y-0053355
X0038382Y-0048355
X0035433Y-0050787
X0037402Y-0043355
X005Y-0044094
X0052362Y-0035531
X0061417Y-0035741
X0043701Y-0034646
X0036614Y-0001969
X0035827Y0001575
X0036614Y0004921
X003622Y0008268
X0036762Y0011811
X0035433Y0015354
X0036614Y0018701
X0020079Y0017323
Y001063
Y0003937
X0019685Y-0002362
X0056693Y000106
X0061811Y0000787
X0085853Y-001378
X0085827Y-0016929
X0100394Y-0030315
X0121653Y-0031496
X0122539Y-0026033
X0116929Y-0021654
X0118898Y-0016929
X0127165Y-0012598
X0134055Y-0006299
X0137598
X0141339Y0000394
X014252Y0013189
X0151181Y0014173
Y001811
X0151782Y0010443
X0149803Y-0009238
X0153543Y-0010433
X0144685Y-0011811
X0152756Y-0049606
Y-005748
Y-0065354
X0149606Y-0080315
X0144095
X0135433Y-0079134
X0121467Y-0074575
X0117323Y-0065354
X0121457Y-0057529
X0121653Y-0052756
X0117717Y-0047293
X0118504Y-0040945
X011811Y-003622
X0072795Y-0053355
X0066102Y-0064085
X-0023622Y-0062992
Y-0060039
Y-0066929
Y-0102362
Y-0106299
Y-0110236
T02
X0478346Y-0305118
X0364567Y-0326378
X0357575Y-0327776
X035748Y-0332677
X0350787Y-0329921
X0274803Y-0372441
X0268504Y-0372047
X0259449Y-0373228
X0250394Y-0375984
Y-0384646
X0243701Y-038937
X0233858Y-0384646
X0227953Y-0383858
X0213386Y-0384646
X0211024Y-0372441
X0205906
X0217323Y-0371654
X0222835Y-0372047
X0237795Y-0371654
X0242897Y-0371864
X0266929Y-0385039
X0022441Y-0167323
X0019685
X0016929
X0017323Y-0147244
X0020079
X0023228
X0255512Y-014685
X0255906Y-0142126
Y-0137008
X025748Y-0150394
X0276083Y-0152559
X0282058Y-0151217
X028189Y-0155905
X0285384Y-0154492
X0284252Y-0144095
X0285827Y-0137795
X0280709
X0276083Y-0141142
X0329656Y-014248
X0329722Y-0145827
X0329919Y-0164008
X0333071Y-0164173
X0335827
X0359842Y-0161024
X0363386Y-016063
X0367717
X041811Y-0153543
X0422835
X0427559
Y-0148819
X0422835
X041811
Y-0144095
X0422835
X0436811Y-0153543
X0442815Y-0161747
Y-0165847
X0439561
X0448425Y-0165354
X0451968
X0455512
X0458661
X0404626Y-0219685
X0404493Y-0224149
X053937Y-022874
X0542913
X0561024Y-0186614
Y-0183465
X0500394Y-0145669
X0496063Y-0145276
X0491732
Y-0149213
X0624409Y-0031496
X0620079Y-003189
X0615748Y-0032283
X0611417Y-0033071
X0611811Y-0038189
X0620866Y-0035827
X0616142Y-0047638
X0613386Y-0050787
X0609547Y-0051181
X0606693Y-0050787
X0601575Y-0053543
X0599213Y-005
X0618898Y-0050787
X0601181Y-0029921
Y-0026772
Y-0023622
X0597244
Y-0026772
Y-0029921
X0544095Y-0042126
X0539764
X0534646
Y-0045276
X0534252Y-0048425
X0534646Y-0051968
X0542913Y-0058268
Y-0061811
Y-0065748
Y-0069291
Y-0072835
X0505118Y-0024016
Y-0020079
X0500787
X0496457
Y-0024016
X0500787Y-0024409
X0468898Y-0039764
X0468504Y-0044488
X0463779
Y-003937
X0458661
Y-0044094
X0460236Y-0087795
Y-009252
X0455118
X0454724Y-0087795
X0445276Y-0103543
X0444488Y-0106299
X0440945Y-0105905
X0436221Y-0106299
X0434347Y-0103743
X0434646Y-0100787
X0431496Y-01
X0425984Y-0109843
X042563Y-0112894
X0423622Y-0115354
X0416535Y-0120768
X0408268Y-0122047
Y-0124409
X0406693Y-0125984
X0369685Y-0123622
Y-0120866
Y-011811
X0366929
Y-0120866
Y-0123622
X0363779
Y-0120866
Y-011811
X0336221Y-0122047
X0333465
X0330315Y-0121653
X0326772Y-0073622
X0322441
Y-0069291
X0326772
X0317717
Y-0073228
X0318898Y-0043307
Y-0039764
Y-0035827
X0324016
Y-0039764
Y-0042913
X0449606Y-0121653
Y-0124803
Y-0128347
X0445669
X0284646
X0286221Y-0124803
X0281496Y-0124409
X027665Y-012881
X0255906Y-0126378
Y-0131496
X0189209Y-0131339
Y-011748
X0241732Y-0074016
X0245669
X0246063Y-0070079
X0241732
X0290945Y-0045276
Y-0040945
X0295276
X0295669Y-0045276
X0295276Y-0035433
X0290945
X015Y-0000787
X0112598Y0000394
X0110589Y0001589
X0108268Y0000394
X0107087Y0009449
X0111024
Y0015354
X0106693
X0107832Y-0010197
X0097408
X0090158Y-000748
X0088257Y-00025
X0084252Y-0002362
Y-0005906
Y-0009055
X0075394Y-0011811
Y-0005709
X007874Y0003543
Y0006693
Y0009843
Y0015354
Y001811
X0093608Y-0003379
X0105282Y-0019291
X0106693Y-0027559
X0101181Y-0038583
X0091339Y-0035039
X0086614Y-003937
X0085039Y-004685
Y-0050787
Y-0053937
X0088583
Y-0050787
Y-0046457
X0086614Y-0056299
X0099606Y-0059842
Y-0063779
X0107874
Y-0059842
X0109843Y-007441
X0105512
Y-0079921
X0109843
X0085039Y-0077559
X0074616Y-0061723
X0066142Y-002126
Y-0016535
Y-0011811
X0061417
X0056693
Y-0016535
X0061417
Y-002126
X0047441
Y-0027362
X0039764Y-0025984
Y-0029528
X0035731Y-0018898
Y-0009843
X0026378Y-001063
X00245Y-0008429
X0024409Y-0016535
X0026378Y-0020472
X0047441Y-0011811
Y-0005709
X0035433Y-0129528
X0032283
X002874
X013937Y-0118898
X0140551Y-0116535
T03
X0311712Y-032989
X0390452
X0448573Y-0294712
X0261082Y-0294702
Y-0215962
X0311722Y-0181769
X0390462
X0448573Y-0215972
T06
X0509597Y-0320167
X0541093
X0556841
X0138297Y-006934
Y-0053592
Y-0022096
T07
X0609449Y-0148189
Y-0138189
X0619449
Y-0148189
Y-0128189
X0609449
Y-0118189
Y-0108189
Y-0098189
X0619449
Y-0108189
Y-0118189
T08
X0298031Y-0155512
Y-0145512
Y-0135512
Y-0125512
Y-0115512
T09
X032126Y-0155669
Y-0145669
Y-0135669
Y-0125669
T10
X-0008465Y-0316781
X-0008465Y-026363
Y-021048
X-0008465Y-0157332
T11
X0001535Y-0326781
Y-0306781
X-0018464
Y-0326781
X-0018465Y-027363
Y-025363
Y-022048
Y-020048
X-0018464Y-0167332
Y-0147332
X0001535
Y-0167332
X0001535Y-020048
Y-022048
Y-025363
Y-027363
T12
X0552709Y-0009055
Y0007445
X0574409
Y-0009055
T13
X0162221Y-0334252
X0174221
X0186221
X0198031
X0209842
X021811Y-0323622
X0058268
Y-0243701
Y-0163779
X021811
T14
X0453193Y-0334056
X0256693
X0256593Y-0177056
X0453193
T15
X0479695Y-0331073
X0582058
Y-0092884
X0479695
X0365581Y-0094557
Y0007806
X0127392
Y-0094557
T16
X0535827Y-0112205
X0424803Y-0038976
X0354035
T17
X0575197Y-0271358
X0194882Y-0078347
T18
X0496457Y-0271358
X0194882Y0000394
T19
X0200876Y-0315719
X0075768Y-0321622
X0078268Y-015978
X020061Y-0171879
T20
X060311Y-0000805
T21
X0Y-0378395
X0Y0
M30
